(kicad_pcb
	(version 20260206)
	(generator "pcbnew")
	(generator_version "10.0")
	(general
		(thickness 1.6)
		(legacy_teardrops no)
	)
	(paper "A4")
	(title_block
		(title "03242023_DA0F0TMBIJ0_F0T_Motherboard_J_brd_V01_OCP.brd")
		(comment 1 "Grand Teton / footprints 1738-1742 of 6105")
	)
	(layers
		(0 "F.Cu" signal "TOP")
		(4 "In1.Cu" signal "GND")
		(6 "In2.Cu" signal "IN1")
		(8 "In3.Cu" signal "GND1")
		(10 "In4.Cu" signal "IN2")
		(12 "In5.Cu" signal "GND2")
		(14 "In6.Cu" signal "IN3")
		(16 "In7.Cu" signal "GND3")
		(18 "In8.Cu" signal "VCC")
		(20 "In9.Cu" signal "VCC1")
		(22 "In10.Cu" signal "GND4")
		(24 "In11.Cu" signal "IN4")
		(26 "In12.Cu" signal "GND5")
		(28 "In13.Cu" signal "IN5")
		(30 "In14.Cu" signal "GND6")
		(32 "In15.Cu" signal "IN6")
		(34 "In16.Cu" signal "GND7")
		(2 "B.Cu" signal "BOTTOM")
		(9 "F.Adhes" user "F.Adhesive")
		(11 "B.Adhes" user "B.Adhesive")
		(13 "F.Paste" user "Package Geometry/Pastemask Top")
		(15 "B.Paste" user "Package Geometry/Pastemask Bottom")
		(5 "F.SilkS" user "Ref Des/Silkscreen Top")
		(7 "B.SilkS" user "Ref Des/Silkscreen Bottom")
		(1 "F.Mask" user "Board Geometry/Soldermask Top")
		(3 "B.Mask" user "Board Geometry/Soldermask Bottom")
		(17 "Dwgs.User" user "User.Drawings")
		(19 "Cmts.User" user "User.Comments")
		(21 "Eco1.User" user "User.Eco1")
		(23 "Eco2.User" user "User.Eco2")
		(25 "Edge.Cuts" user "Board Geometry/Outline")
		(27 "Margin" user)
		(31 "F.CrtYd" user "Package Geometry/Place Bound Top")
		(29 "B.CrtYd" user "Package Geometry/Place Bound Bottom")
		(35 "F.Fab" user "Ref Des/Assembly Top")
		(33 "B.Fab" user "Ref Des/Assembly Bottom")
	)
	(footprint ""
		(layer "F.Cu")
		(at 384.652012 -347.959426)
		(property "Reference" "PR132"
			(at 0 0 0)
			(layer "F.SilkS")
			(hide yes)
			(effects
				(font
					(size 1.27 1.27)
				)
			)
		)
		(property "Value" ""
			(at 0 0 0)
			(layer "F.Fab")
			(effects
				(font
					(size 1.27 1.27)
				)
			)
		)
		(duplicate_pad_numbers_are_jumpers no)
		(fp_line
			(start -0.7874 -0.4064)
			(end 0.7874 -0.4064)
			(stroke
				(width 0.1524)
				(type default)
			)
			(layer "F.SilkS")
		)
		(fp_line
			(start -0.7874 0.4064)
			(end -0.7874 -0.4064)
			(stroke
				(width 0.1524)
				(type default)
			)
			(layer "F.SilkS")
		)
		(fp_line
			(start 0.7874 -0.4064)
			(end 0.7874 0.4064)
			(stroke
				(width 0.1524)
				(type default)
			)
			(layer "F.SilkS")
		)
		(fp_line
			(start 0.7874 0.4064)
			(end -0.7874 0.4064)
			(stroke
				(width 0.1524)
				(type default)
			)
			(layer "F.SilkS")
		)
		(fp_line
			(start -0.67945 -0.305054)
			(end -0.12065 -0.305054)
			(stroke
				(width 0.1)
				(type default)
			)
			(layer "F.Fab")
		)
		(fp_line
			(start -0.67945 0.3048)
			(end -0.67945 -0.305054)
			(stroke
				(width 0.1)
				(type default)
			)
			(layer "F.Fab")
		)
		(fp_line
			(start -0.12065 -0.305054)
			(end -0.12065 -0.2794)
			(stroke
				(width 0.1)
				(type default)
			)
			(layer "F.Fab")
		)
		(fp_line
			(start -0.12065 -0.2794)
			(end 0.12065 -0.2794)
			(stroke
				(width 0.1)
				(type default)
			)
			(layer "F.Fab")
		)
		(fp_line
			(start -0.12065 0.2794)
			(end -0.12065 0.3048)
			(stroke
				(width 0.1)
				(type default)
			)
			(layer "F.Fab")
		)
		(fp_line
			(start -0.12065 0.3048)
			(end -0.67945 0.3048)
			(stroke
				(width 0.1)
				(type default)
			)
			(layer "F.Fab")
		)
		(fp_line
			(start 0.120396 0.2794)
			(end -0.12065 0.2794)
			(stroke
				(width 0.1)
				(type default)
			)
			(layer "F.Fab")
		)
		(fp_line
			(start 0.120396 0.3048)
			(end 0.120396 0.2794)
			(stroke
				(width 0.1)
				(type default)
			)
			(layer "F.Fab")
		)
		(fp_line
			(start 0.12065 -0.3048)
			(end 0.67945 -0.3048)
			(stroke
				(width 0.1)
				(type default)
			)
			(layer "F.Fab")
		)
		(fp_line
			(start 0.12065 -0.2794)
			(end 0.12065 -0.3048)
			(stroke
				(width 0.1)
				(type default)
			)
			(layer "F.Fab")
		)
		(fp_line
			(start 0.67945 -0.3048)
			(end 0.67945 0.3048)
			(stroke
				(width 0.1)
				(type default)
			)
			(layer "F.Fab")
		)
		(fp_line
			(start 0.67945 0.3048)
			(end 0.120396 0.3048)
			(stroke
				(width 0.1)
				(type default)
			)
			(layer "F.Fab")
		)
		(pad "1" smd circle
			(at -0.40005 0)
			(size 0 0)
			(layers "F.Cu" "F.Mask" "F.Paste")
			(net "PVCCIN_CPU0_LSET8")
		)
		(pad "2" smd circle
			(at 0.40005 0)
			(size 0 0)
			(layers "F.Cu" "F.Mask" "F.Paste")
			(net "GND")
		)
	)
	(footprint ""
		(layer "F.Cu")
		(at 155.136088 -76.244958 180)
		(property "Reference" "U143"
			(at -2.853944 -4.426712 0)
			(unlocked yes)
			(layer "F.SilkS")
			(effects
				(font
					(size 0.7874 0.5842)
					(thickness 0.1524)
				)
				(justify left)
			)
		)
		(property "Value" ""
			(at 0 0 180)
			(layer "F.Fab")
			(effects
				(font
					(size 1.27 1.27)
				)
			)
		)
		(duplicate_pad_numbers_are_jumpers no)
		(fp_line
			(start 2.161032 3.299968)
			(end -2.161032 3.299968)
			(stroke
				(width 0.1524)
				(type default)
			)
			(layer "F.SilkS")
		)
		(fp_line
			(start 2.161032 -3.299968)
			(end 2.161032 3.299968)
			(stroke
				(width 0.1524)
				(type default)
			)
			(layer "F.SilkS")
		)
		(fp_line
			(start 1.013968 -3.299968)
			(end 2.161032 -3.299968)
			(stroke
				(width 0.1524)
				(type default)
			)
			(layer "F.SilkS")
		)
		(fp_line
			(start 0 -2.54)
			(end 1.013968 -3.299968)
			(stroke
				(width 0.1524)
				(type default)
			)
			(layer "F.SilkS")
		)
		(fp_line
			(start -1.013968 -3.299968)
			(end 0 -2.54)
			(stroke
				(width 0.1524)
				(type default)
			)
			(layer "F.SilkS")
		)
		(fp_line
			(start -2.161032 3.299968)
			(end -2.161032 -3.299968)
			(stroke
				(width 0.1524)
				(type default)
			)
			(layer "F.SilkS")
		)
		(fp_line
			(start -2.161032 -3.299968)
			(end -1.013968 -3.299968)
			(stroke
				(width 0.1524)
				(type default)
			)
			(layer "F.SilkS")
		)
		(fp_poly
			(pts
				(xy -3.556 -2.925064) (xy -4.572 -2.417064) (xy -4.572 -3.433064)
			)
			(stroke
				(width 0)
				(type default)
			)
			(fill yes)
			(layer "F.SilkS")
		)
		(fp_line
			(start 2.249932 3.299968)
			(end 2.249932 -3.299968)
			(stroke
				(width 0.1)
				(type default)
			)
			(layer "F.Fab")
		)
		(fp_line
			(start 2.249932 -3.299968)
			(end -2.249932 -3.299968)
			(stroke
				(width 0.1)
				(type default)
			)
			(layer "F.Fab")
		)
		(fp_line
			(start -2.249932 3.299968)
			(end 2.249932 3.299968)
			(stroke
				(width 0.1)
				(type default)
			)
			(layer "F.Fab")
		)
		(fp_line
			(start -2.249932 -3.299968)
			(end -2.249932 3.299968)
			(stroke
				(width 0.1)
				(type default)
			)
			(layer "F.Fab")
		)
		(fp_poly
			(pts
				(xy -4.572 -3.433064) (xy -4.572 -2.417064) (xy -3.556 -2.925064)
			)
			(stroke
				(width 0)
				(type default)
			)
			(fill yes)
			(layer "F.Fab")
		)
		(pad "1" smd rect
			(at -2.84988 -2.925064 90)
			(size 0.4064 1.1176)
			(layers "F.Cu" "F.Mask" "F.Paste")
			(net "PCA9543_S3M_ADDR0")
		)
		(pad "2" smd rect
			(at -2.84988 -2.275078 90)
			(size 0.4064 1.1176)
			(layers "F.Cu" "F.Mask" "F.Paste")
			(net "PCA9543_S3M_ADDR1")
		)
		(pad "3" smd rect
			(at -2.84988 -1.625092 90)
			(size 0.4064 1.1176)
			(layers "F.Cu" "F.Mask" "F.Paste")
			(net "RST_SMB_S3M_N")
		)
		(pad "4" smd rect
			(at -2.84988 -0.975106 90)
			(size 0.4064 1.1176)
			(layers "F.Cu" "F.Mask" "F.Paste")
			(net "PCA9543_S3M_INT0_N")
		)
		(pad "5" smd rect
			(at -2.84988 -0.32512 90)
			(size 0.4064 1.1176)
			(layers "F.Cu" "F.Mask" "F.Paste")
			(net "SMB_S3M_CPU0_3V3AUX_SDA_R")
		)
		(pad "6" smd rect
			(at -2.84988 0.32512 90)
			(size 0.4064 1.1176)
			(layers "F.Cu" "F.Mask" "F.Paste")
			(net "SMB_S3M_CPU0_3V3AUX_SCL_R")
		)
		(pad "7" smd rect
			(at -2.84988 0.975106 90)
			(size 0.4064 1.1176)
			(layers "F.Cu" "F.Mask" "F.Paste")
			(net "PCA9543_S3M_INT1_N")
		)
		(pad "8" smd rect
			(at -2.84988 1.625092 90)
			(size 0.4064 1.1176)
			(layers "F.Cu" "F.Mask" "F.Paste")
			(net "SMB_S3M_CPU1_3V3AUX_SDA_R")
		)
		(pad "9" smd rect
			(at -2.84988 2.275078 90)
			(size 0.4064 1.1176)
			(layers "F.Cu" "F.Mask" "F.Paste")
			(net "SMB_S3M_CPU1_3V3AUX_SCL_R")
		)
		(pad "10" smd rect
			(at -2.84988 2.925064 90)
			(size 0.4064 1.1176)
			(layers "F.Cu" "F.Mask" "F.Paste")
			(net "GND")
		)
		(pad "11" smd rect
			(at 2.84988 2.925064 90)
			(size 0.4064 1.1176)
			(layers "F.Cu" "F.Mask" "F.Paste")
			(net "PCA9543_S3M_INT2_N")
		)
		(pad "12" smd rect
			(at 2.84988 2.275078 90)
			(size 0.4064 1.1176)
			(layers "F.Cu" "F.Mask" "F.Paste")
			(net "SMB_S3M_CPU0_PIROM_3V3AUX_SDA_R")
		)
		(pad "13" smd rect
			(at 2.84988 1.625092 90)
			(size 0.4064 1.1176)
			(layers "F.Cu" "F.Mask" "F.Paste")
			(net "SMB_S3M_CPU0_PIROM_3V3AUX_SCL_R")
		)
		(pad "14" smd rect
			(at 2.84988 0.975106 90)
			(size 0.4064 1.1176)
			(layers "F.Cu" "F.Mask" "F.Paste")
			(net "PCA9543_S3M_INT3_N")
		)
		(pad "15" smd rect
			(at 2.84988 0.32512 90)
			(size 0.4064 1.1176)
			(layers "F.Cu" "F.Mask" "F.Paste")
			(net "SMB_S3M_CPU1_PIROM_3V3AUX_SDA_R")
		)
		(pad "16" smd rect
			(at 2.84988 -0.32512 90)
			(size 0.4064 1.1176)
			(layers "F.Cu" "F.Mask" "F.Paste")
			(net "SMB_S3M_CPU1_PIROM_3V3AUX_SCL_R")
		)
		(pad "17" smd rect
			(at 2.84988 -0.975106 90)
			(size 0.4064 1.1176)
			(layers "F.Cu" "F.Mask" "F.Paste")
			(net "PCA9545_S3M_INT_N")
		)
		(pad "18" smd rect
			(at 2.84988 -1.625092 90)
			(size 0.4064 1.1176)
			(layers "F.Cu" "F.Mask" "F.Paste")
			(net "SMB_S3M_CPU_3V3AUX_SCL")
		)
		(pad "19" smd rect
			(at 2.84988 -2.275078 90)
			(size 0.4064 1.1176)
			(layers "F.Cu" "F.Mask" "F.Paste")
			(net "SMB_S3M_CPU_3V3AUX_SDA")
		)
		(pad "20" smd rect
			(at 2.84988 -2.925064 90)
			(size 0.4064 1.1176)
			(layers "F.Cu" "F.Mask" "F.Paste")
			(net "P3V3_AUX")
		)
	)
	(footprint ""
		(layer "F.Cu")
		(at 193.95948 -349.367348 180)
		(property "Reference" "R1229"
			(at 0 0 180)
			(layer "F.SilkS")
			(hide yes)
			(effects
				(font
					(size 1.27 1.27)
				)
			)
		)
		(property "Value" ""
			(at 0 0 180)
			(layer "F.Fab")
			(effects
				(font
					(size 1.27 1.27)
				)
			)
		)
		(duplicate_pad_numbers_are_jumpers no)
		(fp_line
			(start 0.7874 0.4064)
			(end -0.7874 0.4064)
			(stroke
				(width 0.1524)
				(type default)
			)
			(layer "F.SilkS")
		)
		(fp_line
			(start 0.7874 -0.4064)
			(end 0.7874 0.4064)
			(stroke
				(width 0.1524)
				(type default)
			)
			(layer "F.SilkS")
		)
		(fp_line
			(start -0.7874 0.4064)
			(end -0.7874 -0.4064)
			(stroke
				(width 0.1524)
				(type default)
			)
			(layer "F.SilkS")
		)
		(fp_line
			(start -0.7874 -0.4064)
			(end 0.7874 -0.4064)
			(stroke
				(width 0.1524)
				(type default)
			)
			(layer "F.SilkS")
		)
		(fp_line
			(start 0.67945 0.3048)
			(end 0.120396 0.3048)
			(stroke
				(width 0.1)
				(type default)
			)
			(layer "F.Fab")
		)
		(fp_line
			(start 0.67945 -0.3048)
			(end 0.67945 0.3048)
			(stroke
				(width 0.1)
				(type default)
			)
			(layer "F.Fab")
		)
		(fp_line
			(start 0.12065 -0.2794)
			(end 0.12065 -0.3048)
			(stroke
				(width 0.1)
				(type default)
			)
			(layer "F.Fab")
		)
		(fp_line
			(start 0.12065 -0.3048)
			(end 0.67945 -0.3048)
			(stroke
				(width 0.1)
				(type default)
			)
			(layer "F.Fab")
		)
		(fp_line
			(start 0.120396 0.3048)
			(end 0.120396 0.2794)
			(stroke
				(width 0.1)
				(type default)
			)
			(layer "F.Fab")
		)
		(fp_line
			(start 0.120396 0.2794)
			(end -0.12065 0.2794)
			(stroke
				(width 0.1)
				(type default)
			)
			(layer "F.Fab")
		)
		(fp_line
			(start -0.12065 0.3048)
			(end -0.67945 0.3048)
			(stroke
				(width 0.1)
				(type default)
			)
			(layer "F.Fab")
		)
		(fp_line
			(start -0.12065 0.2794)
			(end -0.12065 0.3048)
			(stroke
				(width 0.1)
				(type default)
			)
			(layer "F.Fab")
		)
		(fp_line
			(start -0.12065 -0.2794)
			(end 0.12065 -0.2794)
			(stroke
				(width 0.1)
				(type default)
			)
			(layer "F.Fab")
		)
		(fp_line
			(start -0.12065 -0.305054)
			(end -0.12065 -0.2794)
			(stroke
				(width 0.1)
				(type default)
			)
			(layer "F.Fab")
		)
		(fp_line
			(start -0.67945 0.3048)
			(end -0.67945 -0.305054)
			(stroke
				(width 0.1)
				(type default)
			)
			(layer "F.Fab")
		)
		(fp_line
			(start -0.67945 -0.305054)
			(end -0.12065 -0.305054)
			(stroke
				(width 0.1)
				(type default)
			)
			(layer "F.Fab")
		)
		(pad "1" smd circle
			(at -0.40005 0 180)
			(size 0 0)
			(layers "F.Cu" "F.Mask" "F.Paste")
			(net "PVNN_TERM_CPU1")
		)
		(pad "2" smd circle
			(at 0.40005 0 180)
			(size 0 0)
			(layers "F.Cu" "F.Mask" "F.Paste")
			(net "PUD_XTAL_CPU1_MODE0")
		)
	)
	(footprint ""
		(layer "F.Cu")
		(at 385.716272 -60.735464 180)
		(property "Reference" "R771"
			(at 0 0 180)
			(layer "F.SilkS")
			(hide yes)
			(effects
				(font
					(size 1.27 1.27)
				)
			)
		)
		(property "Value" ""
			(at 0 0 180)
			(layer "F.Fab")
			(effects
				(font
					(size 1.27 1.27)
				)
			)
		)
		(duplicate_pad_numbers_are_jumpers no)
		(fp_line
			(start 0.7874 0.4064)
			(end -0.7874 0.4064)
			(stroke
				(width 0.1524)
				(type default)
			)
			(layer "F.SilkS")
		)
		(fp_line
			(start 0.7874 -0.4064)
			(end 0.7874 0.4064)
			(stroke
				(width 0.1524)
				(type default)
			)
			(layer "F.SilkS")
		)
		(fp_line
			(start -0.7874 0.4064)
			(end -0.7874 -0.4064)
			(stroke
				(width 0.1524)
				(type default)
			)
			(layer "F.SilkS")
		)
		(fp_line
			(start -0.7874 -0.4064)
			(end 0.7874 -0.4064)
			(stroke
				(width 0.1524)
				(type default)
			)
			(layer "F.SilkS")
		)
		(fp_line
			(start 0.67945 0.3048)
			(end 0.120396 0.3048)
			(stroke
				(width 0.1)
				(type default)
			)
			(layer "F.Fab")
		)
		(fp_line
			(start 0.67945 -0.3048)
			(end 0.67945 0.3048)
			(stroke
				(width 0.1)
				(type default)
			)
			(layer "F.Fab")
		)
		(fp_line
			(start 0.12065 -0.2794)
			(end 0.12065 -0.3048)
			(stroke
				(width 0.1)
				(type default)
			)
			(layer "F.Fab")
		)
		(fp_line
			(start 0.12065 -0.3048)
			(end 0.67945 -0.3048)
			(stroke
				(width 0.1)
				(type default)
			)
			(layer "F.Fab")
		)
		(fp_line
			(start 0.120396 0.3048)
			(end 0.120396 0.2794)
			(stroke
				(width 0.1)
				(type default)
			)
			(layer "F.Fab")
		)
		(fp_line
			(start 0.120396 0.2794)
			(end -0.12065 0.2794)
			(stroke
				(width 0.1)
				(type default)
			)
			(layer "F.Fab")
		)
		(fp_line
			(start -0.12065 0.3048)
			(end -0.67945 0.3048)
			(stroke
				(width 0.1)
				(type default)
			)
			(layer "F.Fab")
		)
		(fp_line
			(start -0.12065 0.2794)
			(end -0.12065 0.3048)
			(stroke
				(width 0.1)
				(type default)
			)
			(layer "F.Fab")
		)
		(fp_line
			(start -0.12065 -0.2794)
			(end 0.12065 -0.2794)
			(stroke
				(width 0.1)
				(type default)
			)
			(layer "F.Fab")
		)
		(fp_line
			(start -0.12065 -0.305054)
			(end -0.12065 -0.2794)
			(stroke
				(width 0.1)
				(type default)
			)
			(layer "F.Fab")
		)
		(fp_line
			(start -0.67945 0.3048)
			(end -0.67945 -0.305054)
			(stroke
				(width 0.1)
				(type default)
			)
			(layer "F.Fab")
		)
		(fp_line
			(start -0.67945 -0.305054)
			(end -0.12065 -0.305054)
			(stroke
				(width 0.1)
				(type default)
			)
			(layer "F.Fab")
		)
		(pad "1" smd circle
			(at -0.40005 0 180)
			(size 0 0)
			(layers "F.Cu" "F.Mask" "F.Paste")
			(net "JTAG_DBP_PCH_DEBUG_CONSENT_N")
		)
		(pad "2" smd circle
			(at 0.40005 0 180)
			(size 0 0)
			(layers "F.Cu" "F.Mask" "F.Paste")
			(net "FM_PCH_CONSENT_STRAP_N")
		)
	)
	(footprint ""
		(layer "F.Cu")
		(at 210.560158 -103.95204 180)
		(property "Reference" "C1562"
			(at 0 0 180)
			(layer "F.SilkS")
			(hide yes)
			(effects
				(font
					(size 1.27 1.27)
				)
			)
		)
		(property "Value" ""
			(at 0 0 180)
			(layer "F.Fab")
			(effects
				(font
					(size 1.27 1.27)
				)
			)
		)
		(duplicate_pad_numbers_are_jumpers no)
		(fp_line
			(start 0.7874 0.4064)
			(end -0.7874 0.4064)
			(stroke
				(width 0.1524)
				(type default)
			)
			(layer "F.SilkS")
		)
		(fp_line
			(start 0.7874 -0.4064)
			(end 0.7874 0.4064)
			(stroke
				(width 0.1524)
				(type default)
			)
			(layer "F.SilkS")
		)
		(fp_line
			(start -0.7874 0.4064)
			(end -0.7874 -0.4064)
			(stroke
				(width 0.1524)
				(type default)
			)
			(layer "F.SilkS")
		)
		(fp_line
			(start -0.7874 -0.4064)
			(end 0.7874 -0.4064)
			(stroke
				(width 0.1524)
				(type default)
			)
			(layer "F.SilkS")
		)
		(fp_line
			(start 0.67945 0.3048)
			(end 0.120396 0.3048)
			(stroke
				(width 0.1)
				(type default)
			)
			(layer "F.Fab")
		)
		(fp_line
			(start 0.67945 -0.3048)
			(end 0.67945 0.3048)
			(stroke
				(width 0.1)
				(type default)
			)
			(layer "F.Fab")
		)
		(fp_line
			(start 0.12065 -0.2794)
			(end 0.12065 -0.3048)
			(stroke
				(width 0.1)
				(type default)
			)
			(layer "F.Fab")
		)
		(fp_line
			(start 0.12065 -0.3048)
			(end 0.67945 -0.3048)
			(stroke
				(width 0.1)
				(type default)
			)
			(layer "F.Fab")
		)
		(fp_line
			(start 0.120396 0.3048)
			(end 0.120396 0.2794)
			(stroke
				(width 0.1)
				(type default)
			)
			(layer "F.Fab")
		)
		(fp_line
			(start 0.120396 0.2794)
			(end -0.12065 0.2794)
			(stroke
				(width 0.1)
				(type default)
			)
			(layer "F.Fab")
		)
		(fp_line
			(start -0.12065 0.3048)
			(end -0.67945 0.3048)
			(stroke
				(width 0.1)
				(type default)
			)
			(layer "F.Fab")
		)
		(fp_line
			(start -0.12065 0.2794)
			(end -0.12065 0.3048)
			(stroke
				(width 0.1)
				(type default)
			)
			(layer "F.Fab")
		)
		(fp_line
			(start -0.12065 -0.2794)
			(end 0.12065 -0.2794)
			(stroke
				(width 0.1)
				(type default)
			)
			(layer "F.Fab")
		)
		(fp_line
			(start -0.12065 -0.305054)
			(end -0.12065 -0.2794)
			(stroke
				(width 0.1)
				(type default)
			)
			(layer "F.Fab")
		)
		(fp_line
			(start -0.67945 0.3048)
			(end -0.67945 -0.305054)
			(stroke
				(width 0.1)
				(type default)
			)
			(layer "F.Fab")
		)
		(fp_line
			(start -0.67945 -0.305054)
			(end -0.12065 -0.305054)
			(stroke
				(width 0.1)
				(type default)
			)
			(layer "F.Fab")
		)
		(pad "1" smd circle
			(at -0.40005 0 180)
			(size 0 0)
			(layers "F.Cu" "F.Mask" "F.Paste")
			(net "U205_VDD")
		)
		(pad "2" smd circle
			(at 0.40005 0 180)
			(size 0 0)
			(layers "F.Cu" "F.Mask" "F.Paste")
			(net "GND")
		)
	)
)
